(kicad_pcb
	(version 20260206)
	(generator "pcbnew")
	(generator_version "10.0")
	(general
		(thickness 1.6)
		(legacy_teardrops no)
	)
	(paper "A4")
	(title_block
		(title "03242023_DA0F0TMBIJ0_F0T_Motherboard_J_brd_V01_OCP.brd")
		(comment 1 "Grand Teton / footprints 20-25 of 6105")
	)
	(layers
		(0 "F.Cu" signal "TOP")
		(4 "In1.Cu" signal "GND")
		(6 "In2.Cu" signal "IN1")
		(8 "In3.Cu" signal "GND1")
		(10 "In4.Cu" signal "IN2")
		(12 "In5.Cu" signal "GND2")
		(14 "In6.Cu" signal "IN3")
		(16 "In7.Cu" signal "GND3")
		(18 "In8.Cu" signal "VCC")
		(20 "In9.Cu" signal "VCC1")
		(22 "In10.Cu" signal "GND4")
		(24 "In11.Cu" signal "IN4")
		(26 "In12.Cu" signal "GND5")
		(28 "In13.Cu" signal "IN5")
		(30 "In14.Cu" signal "GND6")
		(32 "In15.Cu" signal "IN6")
		(34 "In16.Cu" signal "GND7")
		(2 "B.Cu" signal "BOTTOM")
		(9 "F.Adhes" user "F.Adhesive")
		(11 "B.Adhes" user "B.Adhesive")
		(13 "F.Paste" user "Package Geometry/Pastemask Top")
		(15 "B.Paste" user "Package Geometry/Pastemask Bottom")
		(5 "F.SilkS" user "Ref Des/Silkscreen Top")
		(7 "B.SilkS" user "Ref Des/Silkscreen Bottom")
		(1 "F.Mask" user "Board Geometry/Soldermask Top")
		(3 "B.Mask" user "Board Geometry/Soldermask Bottom")
		(17 "Dwgs.User" user "User.Drawings")
		(19 "Cmts.User" user "User.Comments")
		(21 "Eco1.User" user "User.Eco1")
		(23 "Eco2.User" user "User.Eco2")
		(25 "Edge.Cuts" user "Board Geometry/Outline")
		(27 "Margin" user)
		(31 "F.CrtYd" user "Package Geometry/Place Bound Top")
		(29 "B.CrtYd" user "Package Geometry/Place Bound Bottom")
		(35 "F.Fab" user "Ref Des/Assembly Top")
		(33 "B.Fab" user "Ref Des/Assembly Bottom")
	)
	(footprint ""
		(layer "F.Cu")
		(at 357.683816 -333.525368 -90)
		(property "Reference" "PC273_P0_3"
			(at 0 0 270)
			(layer "F.SilkS")
			(hide yes)
			(effects
				(font
					(size 1.27 1.27)
				)
			)
		)
		(property "Value" ""
			(at 0 0 270)
			(layer "F.Fab")
			(effects
				(font
					(size 1.27 1.27)
				)
			)
		)
		(duplicate_pad_numbers_are_jumpers no)
		(fp_line
			(start -0.7874 0.4064)
			(end -0.7874 -0.4064)
			(stroke
				(width 0.1524)
				(type default)
			)
			(layer "F.SilkS")
		)
		(fp_line
			(start 0.7874 0.4064)
			(end -0.7874 0.4064)
			(stroke
				(width 0.1524)
				(type default)
			)
			(layer "F.SilkS")
		)
		(fp_line
			(start -0.7874 -0.4064)
			(end 0.7874 -0.4064)
			(stroke
				(width 0.1524)
				(type default)
			)
			(layer "F.SilkS")
		)
		(fp_line
			(start 0.7874 -0.4064)
			(end 0.7874 0.4064)
			(stroke
				(width 0.1524)
				(type default)
			)
			(layer "F.SilkS")
		)
		(fp_line
			(start -0.67945 0.3048)
			(end -0.67945 -0.305054)
			(stroke
				(width 0.1)
				(type default)
			)
			(layer "F.Fab")
		)
		(fp_line
			(start -0.12065 0.3048)
			(end -0.67945 0.3048)
			(stroke
				(width 0.1)
				(type default)
			)
			(layer "F.Fab")
		)
		(fp_line
			(start 0.120396 0.3048)
			(end 0.120396 0.2794)
			(stroke
				(width 0.1)
				(type default)
			)
			(layer "F.Fab")
		)
		(fp_line
			(start 0.67945 0.3048)
			(end 0.120396 0.3048)
			(stroke
				(width 0.1)
				(type default)
			)
			(layer "F.Fab")
		)
		(fp_line
			(start -0.12065 0.2794)
			(end -0.12065 0.3048)
			(stroke
				(width 0.1)
				(type default)
			)
			(layer "F.Fab")
		)
		(fp_line
			(start 0.120396 0.2794)
			(end -0.12065 0.2794)
			(stroke
				(width 0.1)
				(type default)
			)
			(layer "F.Fab")
		)
		(fp_line
			(start -0.12065 -0.2794)
			(end 0.12065 -0.2794)
			(stroke
				(width 0.1)
				(type default)
			)
			(layer "F.Fab")
		)
		(fp_line
			(start 0.12065 -0.2794)
			(end 0.12065 -0.3048)
			(stroke
				(width 0.1)
				(type default)
			)
			(layer "F.Fab")
		)
		(fp_line
			(start 0.12065 -0.3048)
			(end 0.67945 -0.3048)
			(stroke
				(width 0.1)
				(type default)
			)
			(layer "F.Fab")
		)
		(fp_line
			(start 0.67945 -0.3048)
			(end 0.67945 0.3048)
			(stroke
				(width 0.1)
				(type default)
			)
			(layer "F.Fab")
		)
		(fp_line
			(start -0.67945 -0.305054)
			(end -0.12065 -0.305054)
			(stroke
				(width 0.1)
				(type default)
			)
			(layer "F.Fab")
		)
		(fp_line
			(start -0.12065 -0.305054)
			(end -0.12065 -0.2794)
			(stroke
				(width 0.1)
				(type default)
			)
			(layer "F.Fab")
		)
		(pad "1" smd circle
			(at -0.40005 0 270)
			(size 0 0)
			(layers "F.Cu" "F.Mask" "F.Paste")
			(net "PVCCIN_CPU0_PVCC")
		)
		(pad "2" smd circle
			(at 0.40005 0 270)
			(size 0 0)
			(layers "F.Cu" "F.Mask" "F.Paste")
			(net "GND")
		)
	)
	(footprint ""
		(layer "F.Cu")
		(at 84.455 -38.699948 90)
		(property "Reference" "U323"
			(at 4.41833 -0.508 0)
			(unlocked yes)
			(layer "F.SilkS")
			(effects
				(font
					(size 0.7874 0.5842)
					(thickness 0.1524)
				)
				(justify left)
			)
		)
		(property "Value" ""
			(at 0 0 90)
			(layer "F.Fab")
			(effects
				(font
					(size 1.27 1.27)
				)
			)
		)
		(duplicate_pad_numbers_are_jumpers no)
		(fp_line
			(start 1.733296 -1.549908)
			(end 0.660908 -1.549908)
			(stroke
				(width 0.1524)
				(type default)
			)
			(layer "F.SilkS")
		)
		(fp_line
			(start 0.660908 -1.549908)
			(end 0 -0.889)
			(stroke
				(width 0.1524)
				(type default)
			)
			(layer "F.SilkS")
		)
		(fp_line
			(start -0.660908 -1.549908)
			(end -1.733296 -1.549908)
			(stroke
				(width 0.1524)
				(type default)
			)
			(layer "F.SilkS")
		)
		(fp_line
			(start -1.733296 -1.549908)
			(end -1.733296 1.549908)
			(stroke
				(width 0.1524)
				(type default)
			)
			(layer "F.SilkS")
		)
		(fp_line
			(start 0 -0.889)
			(end -0.660908 -1.549908)
			(stroke
				(width 0.1524)
				(type default)
			)
			(layer "F.SilkS")
		)
		(fp_line
			(start 1.733296 1.549908)
			(end 1.733296 -1.549908)
			(stroke
				(width 0.1524)
				(type default)
			)
			(layer "F.SilkS")
		)
		(fp_line
			(start -1.733296 1.549908)
			(end 1.733296 1.549908)
			(stroke
				(width 0.1524)
				(type default)
			)
			(layer "F.SilkS")
		)
		(fp_poly
			(pts
				(xy -2.299716 -2.047748) (xy -2.646934 -1.676654) (xy -2.102358 -1.51511)
			)
			(stroke
				(width 0)
				(type default)
			)
			(fill yes)
			(layer "F.SilkS")
		)
		(fp_line
			(start 0.849884 -1.549908)
			(end -0.849884 -1.549908)
			(stroke
				(width 0.1)
				(type default)
			)
			(layer "F.Fab")
		)
		(fp_line
			(start -0.849884 -1.549908)
			(end -0.849884 1.549908)
			(stroke
				(width 0.1)
				(type default)
			)
			(layer "F.Fab")
		)
		(fp_line
			(start 0.849884 1.549908)
			(end 0.849884 -1.549908)
			(stroke
				(width 0.1)
				(type default)
			)
			(layer "F.Fab")
		)
		(fp_line
			(start -0.849884 1.549908)
			(end 0.849884 1.549908)
			(stroke
				(width 0.1)
				(type default)
			)
			(layer "F.Fab")
		)
		(fp_poly
			(pts
				(xy -2.4384 -1.20396) (xy -2.4384 -0.69596) (xy -1.9304 -0.94996)
			)
			(stroke
				(width 0)
				(type default)
			)
			(fill yes)
			(layer "F.Fab")
		)
		(pad "1" smd rect
			(at -1.199896 -0.94996)
			(size 0.5588 0.8128)
			(layers "F.Cu" "F.Mask" "F.Paste")
			(net "HP_OCP_V3_2_RST_R")
		)
		(pad "2" smd rect
			(at -1.199896 0)
			(size 0.5588 0.8128)
			(layers "F.Cu" "F.Mask" "F.Paste")
			(net "HP_LVC3_OCP_V3_2_P12V_PWRGD")
		)
		(pad "3" smd rect
			(at -1.199896 0.94996)
			(size 0.5588 0.8128)
			(layers "F.Cu" "F.Mask" "F.Paste")
			(net "GND")
		)
		(pad "4" smd rect
			(at 1.199896 0.94996)
			(size 0.5588 0.8128)
			(layers "F.Cu" "F.Mask" "F.Paste")
			(net "HP_LVC3_OCP_V3_2_PWRGD")
		)
		(pad "5" smd rect
			(at 1.199896 -0.94996)
			(size 0.5588 0.8128)
			(layers "F.Cu" "F.Mask" "F.Paste")
			(net "P3V3_AUX")
		)
	)
	(footprint ""
		(layer "F.Cu")
		(at 169.441622 -421.527478 180)
		(property "Reference" "R3463"
			(at 0 0 180)
			(layer "F.SilkS")
			(hide yes)
			(effects
				(font
					(size 1.27 1.27)
				)
			)
		)
		(property "Value" ""
			(at 0 0 180)
			(layer "F.Fab")
			(effects
				(font
					(size 1.27 1.27)
				)
			)
		)
		(duplicate_pad_numbers_are_jumpers no)
		(fp_line
			(start 0.7874 0.4064)
			(end -0.7874 0.4064)
			(stroke
				(width 0.1524)
				(type default)
			)
			(layer "F.SilkS")
		)
		(fp_line
			(start 0.7874 -0.4064)
			(end 0.7874 0.4064)
			(stroke
				(width 0.1524)
				(type default)
			)
			(layer "F.SilkS")
		)
		(fp_line
			(start -0.7874 0.4064)
			(end -0.7874 -0.4064)
			(stroke
				(width 0.1524)
				(type default)
			)
			(layer "F.SilkS")
		)
		(fp_line
			(start -0.7874 -0.4064)
			(end 0.7874 -0.4064)
			(stroke
				(width 0.1524)
				(type default)
			)
			(layer "F.SilkS")
		)
		(fp_line
			(start 0.67945 0.3048)
			(end 0.120396 0.3048)
			(stroke
				(width 0.1)
				(type default)
			)
			(layer "F.Fab")
		)
		(fp_line
			(start 0.67945 -0.3048)
			(end 0.67945 0.3048)
			(stroke
				(width 0.1)
				(type default)
			)
			(layer "F.Fab")
		)
		(fp_line
			(start 0.12065 -0.2794)
			(end 0.12065 -0.3048)
			(stroke
				(width 0.1)
				(type default)
			)
			(layer "F.Fab")
		)
		(fp_line
			(start 0.12065 -0.3048)
			(end 0.67945 -0.3048)
			(stroke
				(width 0.1)
				(type default)
			)
			(layer "F.Fab")
		)
		(fp_line
			(start 0.120396 0.3048)
			(end 0.120396 0.2794)
			(stroke
				(width 0.1)
				(type default)
			)
			(layer "F.Fab")
		)
		(fp_line
			(start 0.120396 0.2794)
			(end -0.12065 0.2794)
			(stroke
				(width 0.1)
				(type default)
			)
			(layer "F.Fab")
		)
		(fp_line
			(start -0.12065 0.3048)
			(end -0.67945 0.3048)
			(stroke
				(width 0.1)
				(type default)
			)
			(layer "F.Fab")
		)
		(fp_line
			(start -0.12065 0.2794)
			(end -0.12065 0.3048)
			(stroke
				(width 0.1)
				(type default)
			)
			(layer "F.Fab")
		)
		(fp_line
			(start -0.12065 -0.2794)
			(end 0.12065 -0.2794)
			(stroke
				(width 0.1)
				(type default)
			)
			(layer "F.Fab")
		)
		(fp_line
			(start -0.12065 -0.305054)
			(end -0.12065 -0.2794)
			(stroke
				(width 0.1)
				(type default)
			)
			(layer "F.Fab")
		)
		(fp_line
			(start -0.67945 0.3048)
			(end -0.67945 -0.305054)
			(stroke
				(width 0.1)
				(type default)
			)
			(layer "F.Fab")
		)
		(fp_line
			(start -0.67945 -0.305054)
			(end -0.12065 -0.305054)
			(stroke
				(width 0.1)
				(type default)
			)
			(layer "F.Fab")
		)
		(pad "1" smd circle
			(at -0.40005 0 180)
			(size 0 0)
			(layers "F.Cu" "F.Mask" "F.Paste")
			(net "GPU_BASE_HMC_READY")
		)
		(pad "2" smd circle
			(at 0.40005 0 180)
			(size 0 0)
			(layers "F.Cu" "F.Mask" "F.Paste")
			(net "GND")
		)
	)
	(footprint ""
		(layer "F.Cu")
		(at 68.085716 -107.37469)
		(property "Reference" "R3722"
			(at 0 0 0)
			(layer "F.SilkS")
			(hide yes)
			(effects
				(font
					(size 1.27 1.27)
				)
			)
		)
		(property "Value" ""
			(at 0 0 0)
			(layer "F.Fab")
			(effects
				(font
					(size 1.27 1.27)
				)
			)
		)
		(duplicate_pad_numbers_are_jumpers no)
		(fp_line
			(start -0.7874 -0.4064)
			(end 0.7874 -0.4064)
			(stroke
				(width 0.1524)
				(type default)
			)
			(layer "F.SilkS")
		)
		(fp_line
			(start -0.7874 0.4064)
			(end -0.7874 -0.4064)
			(stroke
				(width 0.1524)
				(type default)
			)
			(layer "F.SilkS")
		)
		(fp_line
			(start 0.7874 -0.4064)
			(end 0.7874 0.4064)
			(stroke
				(width 0.1524)
				(type default)
			)
			(layer "F.SilkS")
		)
		(fp_line
			(start 0.7874 0.4064)
			(end -0.7874 0.4064)
			(stroke
				(width 0.1524)
				(type default)
			)
			(layer "F.SilkS")
		)
		(fp_line
			(start -0.67945 -0.305054)
			(end -0.12065 -0.305054)
			(stroke
				(width 0.1)
				(type default)
			)
			(layer "F.Fab")
		)
		(fp_line
			(start -0.67945 0.3048)
			(end -0.67945 -0.305054)
			(stroke
				(width 0.1)
				(type default)
			)
			(layer "F.Fab")
		)
		(fp_line
			(start -0.12065 -0.305054)
			(end -0.12065 -0.2794)
			(stroke
				(width 0.1)
				(type default)
			)
			(layer "F.Fab")
		)
		(fp_line
			(start -0.12065 -0.2794)
			(end 0.12065 -0.2794)
			(stroke
				(width 0.1)
				(type default)
			)
			(layer "F.Fab")
		)
		(fp_line
			(start -0.12065 0.2794)
			(end -0.12065 0.3048)
			(stroke
				(width 0.1)
				(type default)
			)
			(layer "F.Fab")
		)
		(fp_line
			(start -0.12065 0.3048)
			(end -0.67945 0.3048)
			(stroke
				(width 0.1)
				(type default)
			)
			(layer "F.Fab")
		)
		(fp_line
			(start 0.120396 0.2794)
			(end -0.12065 0.2794)
			(stroke
				(width 0.1)
				(type default)
			)
			(layer "F.Fab")
		)
		(fp_line
			(start 0.120396 0.3048)
			(end 0.120396 0.2794)
			(stroke
				(width 0.1)
				(type default)
			)
			(layer "F.Fab")
		)
		(fp_line
			(start 0.12065 -0.3048)
			(end 0.67945 -0.3048)
			(stroke
				(width 0.1)
				(type default)
			)
			(layer "F.Fab")
		)
		(fp_line
			(start 0.12065 -0.2794)
			(end 0.12065 -0.3048)
			(stroke
				(width 0.1)
				(type default)
			)
			(layer "F.Fab")
		)
		(fp_line
			(start 0.67945 -0.3048)
			(end 0.67945 0.3048)
			(stroke
				(width 0.1)
				(type default)
			)
			(layer "F.Fab")
		)
		(fp_line
			(start 0.67945 0.3048)
			(end 0.120396 0.3048)
			(stroke
				(width 0.1)
				(type default)
			)
			(layer "F.Fab")
		)
		(pad "1" smd circle
			(at -0.40005 0)
			(size 0 0)
			(layers "F.Cu" "F.Mask" "F.Paste")
			(net "SMB_LM75_3_3V3AUX_SDA_R")
		)
		(pad "2" smd circle
			(at 0.40005 0)
			(size 0 0)
			(layers "F.Cu" "F.Mask" "F.Paste")
			(net "SMB_LM75_3_3V3AUX_SDA")
		)
	)
	(footprint ""
		(layer "F.Cu")
		(at 309.522622 -33.772348 180)
		(property "Reference" "R1600"
			(at 0 0 180)
			(layer "F.SilkS")
			(hide yes)
			(effects
				(font
					(size 1.27 1.27)
				)
			)
		)
		(property "Value" ""
			(at 0 0 180)
			(layer "F.Fab")
			(effects
				(font
					(size 1.27 1.27)
				)
			)
		)
		(duplicate_pad_numbers_are_jumpers no)
		(fp_line
			(start 0.7874 0.4064)
			(end -0.7874 0.4064)
			(stroke
				(width 0.1524)
				(type default)
			)
			(layer "F.SilkS")
		)
		(fp_line
			(start 0.7874 -0.4064)
			(end 0.7874 0.4064)
			(stroke
				(width 0.1524)
				(type default)
			)
			(layer "F.SilkS")
		)
		(fp_line
			(start -0.7874 0.4064)
			(end -0.7874 -0.4064)
			(stroke
				(width 0.1524)
				(type default)
			)
			(layer "F.SilkS")
		)
		(fp_line
			(start -0.7874 -0.4064)
			(end 0.7874 -0.4064)
			(stroke
				(width 0.1524)
				(type default)
			)
			(layer "F.SilkS")
		)
		(fp_line
			(start 0.67945 0.3048)
			(end 0.120396 0.3048)
			(stroke
				(width 0.1)
				(type default)
			)
			(layer "F.Fab")
		)
		(fp_line
			(start 0.67945 -0.3048)
			(end 0.67945 0.3048)
			(stroke
				(width 0.1)
				(type default)
			)
			(layer "F.Fab")
		)
		(fp_line
			(start 0.12065 -0.2794)
			(end 0.12065 -0.3048)
			(stroke
				(width 0.1)
				(type default)
			)
			(layer "F.Fab")
		)
		(fp_line
			(start 0.12065 -0.3048)
			(end 0.67945 -0.3048)
			(stroke
				(width 0.1)
				(type default)
			)
			(layer "F.Fab")
		)
		(fp_line
			(start 0.120396 0.3048)
			(end 0.120396 0.2794)
			(stroke
				(width 0.1)
				(type default)
			)
			(layer "F.Fab")
		)
		(fp_line
			(start 0.120396 0.2794)
			(end -0.12065 0.2794)
			(stroke
				(width 0.1)
				(type default)
			)
			(layer "F.Fab")
		)
		(fp_line
			(start -0.12065 0.3048)
			(end -0.67945 0.3048)
			(stroke
				(width 0.1)
				(type default)
			)
			(layer "F.Fab")
		)
		(fp_line
			(start -0.12065 0.2794)
			(end -0.12065 0.3048)
			(stroke
				(width 0.1)
				(type default)
			)
			(layer "F.Fab")
		)
		(fp_line
			(start -0.12065 -0.2794)
			(end 0.12065 -0.2794)
			(stroke
				(width 0.1)
				(type default)
			)
			(layer "F.Fab")
		)
		(fp_line
			(start -0.12065 -0.305054)
			(end -0.12065 -0.2794)
			(stroke
				(width 0.1)
				(type default)
			)
			(layer "F.Fab")
		)
		(fp_line
			(start -0.67945 0.3048)
			(end -0.67945 -0.305054)
			(stroke
				(width 0.1)
				(type default)
			)
			(layer "F.Fab")
		)
		(fp_line
			(start -0.67945 -0.305054)
			(end -0.12065 -0.305054)
			(stroke
				(width 0.1)
				(type default)
			)
			(layer "F.Fab")
		)
		(pad "1" smd circle
			(at -0.40005 0 180)
			(size 0 0)
			(layers "F.Cu" "F.Mask" "F.Paste")
			(net "IRQ_SML0_ALERT_N")
		)
		(pad "2" smd circle
			(at 0.40005 0 180)
			(size 0 0)
			(layers "F.Cu" "F.Mask" "F.Paste")
			(net "IRQ_SML0_ALERT_R_N")
		)
	)
	(footprint ""
		(layer "F.Cu")
		(at 205.968092 -101.006656)
		(property "Reference" "Q34"
			(at -3.937 -1.92913 0)
			(unlocked yes)
			(layer "F.SilkS")
			(effects
				(font
					(size 0.7874 0.5842)
					(thickness 0.1524)
				)
				(justify left)
			)
		)
		(property "Value" ""
			(at 0 0 0)
			(layer "F.Fab")
			(effects
				(font
					(size 1.27 1.27)
				)
			)
		)
		(duplicate_pad_numbers_are_jumpers no)
		(fp_line
			(start -1.603248 -1.500124)
			(end 1.603248 -1.500124)
			(stroke
				(width 0.1524)
				(type default)
			)
			(layer "F.SilkS")
		)
		(fp_line
			(start -1.603248 1.500124)
			(end -1.603248 -1.500124)
			(stroke
				(width 0.1524)
				(type default)
			)
			(layer "F.SilkS")
		)
		(fp_line
			(start 1.603248 -1.500124)
			(end 1.603248 1.500124)
			(stroke
				(width 0.1524)
				(type default)
			)
			(layer "F.SilkS")
		)
		(fp_line
			(start 1.603248 1.500124)
			(end -1.603248 1.500124)
			(stroke
				(width 0.1524)
				(type default)
			)
			(layer "F.SilkS")
		)
		(fp_line
			(start -1.249934 -1.169924)
			(end -1.249934 -0.729996)
			(stroke
				(width 0.1)
				(type default)
			)
			(layer "F.Fab")
		)
		(fp_line
			(start -1.249934 -0.729996)
			(end -0.6985 -0.729996)
			(stroke
				(width 0.1)
				(type default)
			)
			(layer "F.Fab")
		)
		(fp_line
			(start -1.249934 0.729996)
			(end -1.249934 1.169924)
			(stroke
				(width 0.1)
				(type default)
			)
			(layer "F.Fab")
		)
		(fp_line
			(start -1.249934 1.169924)
			(end -0.700024 1.169924)
			(stroke
				(width 0.1)
				(type default)
			)
			(layer "F.Fab")
		)
		(fp_line
			(start -0.700024 -1.500124)
			(end -0.700024 -1.169924)
			(stroke
				(width 0.1)
				(type default)
			)
			(layer "F.Fab")
		)
		(fp_line
			(start -0.700024 -1.169924)
			(end -1.249934 -1.169924)
			(stroke
				(width 0.1)
				(type default)
			)
			(layer "F.Fab")
		)
		(fp_line
			(start -0.700024 1.169924)
			(end -0.700024 1.500124)
			(stroke
				(width 0.1)
				(type default)
			)
			(layer "F.Fab")
		)
		(fp_line
			(start -0.700024 1.500124)
			(end 0.700024 1.500124)
			(stroke
				(width 0.1)
				(type default)
			)
			(layer "F.Fab")
		)
		(fp_line
			(start -0.6985 -0.729996)
			(end -0.6985 0.729996)
			(stroke
				(width 0.1)
				(type default)
			)
			(layer "F.Fab")
		)
		(fp_line
			(start -0.6985 0.729996)
			(end -1.249934 0.729996)
			(stroke
				(width 0.1)
				(type default)
			)
			(layer "F.Fab")
		)
		(fp_line
			(start 0.700024 -1.500124)
			(end -0.700024 -1.500124)
			(stroke
				(width 0.1)
				(type default)
			)
			(layer "F.Fab")
		)
		(fp_line
			(start 0.700024 -0.219964)
			(end 0.700024 -1.500124)
			(stroke
				(width 0.1)
				(type default)
			)
			(layer "F.Fab")
		)
		(fp_line
			(start 0.700024 0.219964)
			(end 1.249934 0.219964)
			(stroke
				(width 0.1)
				(type default)
			)
			(layer "F.Fab")
		)
		(fp_line
			(start 0.700024 1.500124)
			(end 0.700024 0.219964)
			(stroke
				(width 0.1)
				(type default)
			)
			(layer "F.Fab")
		)
		(fp_line
			(start 1.249934 -0.219964)
			(end 0.700024 -0.219964)
			(stroke
				(width 0.1)
				(type default)
			)
			(layer "F.Fab")
		)
		(fp_line
			(start 1.249934 0.219964)
			(end 1.249934 -0.219964)
			(stroke
				(width 0.1)
				(type default)
			)
			(layer "F.Fab")
		)
		(fp_rect
			(start -0.700024 1.500124)
			(end 0.700024 -1.500124)
			(stroke
				(width 0)
				(type default)
			)
			(fill no)
			(layer "F.Fab")
		)
		(pad "D" smd rect
			(at 0.999998 0 270)
			(size 0.8128 0.9144)
			(layers "F.Cu" "F.Mask" "F.Paste")
			(net "RST_RTCRST_N")
		)
		(pad "G" smd rect
			(at -0.999998 -0.94996 270)
			(size 0.8128 0.9144)
			(layers "F.Cu" "F.Mask" "F.Paste")
			(net "RST_PFR_OVR_RTC")
		)
		(pad "S" smd rect
			(at -0.999998 0.94996 270)
			(size 0.8128 0.9144)
			(layers "F.Cu" "F.Mask" "F.Paste")
			(net "GND")
		)
	)
)
